(kicad_pcb
	(version 20260206)
	(generator "pcbnew")
	(generator_version "10.0")
	(general
		(thickness 1.6)
		(legacy_teardrops no)
	)
	(paper "A4")
	(title_block
		(title "baseboard — 13948-1b.1110WZS1818.brd")
		(comment 1 "Honey Badger (Wiwynn) / footprints 2003-2011 of 2523")
	)
	(layers
		(0 "F.Cu" signal "TOP")
		(4 "In1.Cu" signal "L2GND")
		(6 "In2.Cu" signal "L3")
		(8 "In3.Cu" signal "L4VCC")
		(10 "In4.Cu" signal "L5VCC")
		(12 "In5.Cu" signal "L6")
		(14 "In6.Cu" signal "L7GND")
		(2 "B.Cu" signal "BOTTOM")
		(9 "F.Adhes" user "F.Adhesive")
		(11 "B.Adhes" user "B.Adhesive")
		(13 "F.Paste" user "Package Geometry/Pastemask Top")
		(15 "B.Paste" user "Package Geometry/Pastemask Bottom")
		(5 "F.SilkS" user "Ref Des/Silkscreen Top")
		(7 "B.SilkS" user "Ref Des/Silkscreen Bottom")
		(1 "F.Mask" user "Board Geometry/Soldermask Top")
		(3 "B.Mask" user "Board Geometry/Soldermask Bottom")
		(17 "Dwgs.User" user "User.Drawings")
		(19 "Cmts.User" user "User.Comments")
		(21 "Eco1.User" user "User.Eco1")
		(23 "Eco2.User" user "User.Eco2")
		(25 "Edge.Cuts" user "Board Geometry/Outline")
		(27 "Margin" user)
		(31 "F.CrtYd" user "Package Geometry/Place Bound Top")
		(29 "B.CrtYd" user "Package Geometry/Place Bound Bottom")
		(35 "F.Fab" user "Ref Des/Assembly Top")
		(33 "B.Fab" user "Ref Des/Assembly Bottom")
	)
	(footprint ""
		(layer "B.Cu")
		(at 110.804706 -53.05298 -90)
		(property "Reference" "SC1007"
			(at 0 0 90)
			(layer "B.SilkS")
			(hide yes)
			(effects
				(font
					(size 1.27 1.27)
				)
				(justify mirror)
			)
		)
		(property "Value" "SCD1U16V2KX-3GP"
			(at -1.1811 -2.7051 270)
			(unlocked yes)
			(layer "B.Fab")
			(hide yes)
			(effects
				(font
					(size 1.016 1.016)
					(thickness 0.1524)
				)
				(justify mirror)
			)
		)
		(property "Device Type" "C402H22"
			(at -1.1811 -4.2291 270)
			(unlocked yes)
			(layer "B.Fab")
			(hide yes)
			(effects
				(font
					(size 1.016 1.016)
					(thickness 0.1524)
				)
				(justify mirror)
			)
		)
		(duplicate_pad_numbers_are_jumpers no)
		(fp_rect
			(start 0.4318 0.9525)
			(end -0.4318 -0.9525)
			(stroke
				(width 0)
				(type default)
			)
			(fill no)
			(layer "B.CrtYd")
		)
		(fp_rect
			(start 0.4318 0.9525)
			(end -0.4318 -0.9525)
			(stroke
				(width 0)
				(type default)
			)
			(fill no)
			(layer "B.Fab")
		)
		(pad "1" smd custom
			(at 0 -0.4445 90)
			(size 0.1524 0.1524)
			(layers "B.Cu" "B.Mask" "B.Paste")
			(net "P1V8_C")
			(options
				(clearance outline)
				(anchor circle)
			)
			(primitives
				(gr_poly
					(pts
						(arc
							(start 0.3048 0.2032)
							(mid 0.275042 0.275042)
							(end 0.2032 0.3048)
						)
						(arc
							(start -0.2032 0.3048)
							(mid -0.275042 0.275042)
							(end -0.3048 0.2032)
						)
						(arc
							(start -0.3048 -0.2032)
							(mid -0.275042 -0.275042)
							(end -0.2032 -0.3048)
						)
						(arc
							(start 0.2032 -0.3048)
							(mid 0.275042 -0.275042)
							(end 0.3048 -0.2032)
						)
					)
					(width 0)
					(fill yes)
				)
			)
		)
		(pad "2" smd custom
			(at 0 0.4445 90)
			(size 0.1524 0.1524)
			(layers "B.Cu" "B.Mask" "B.Paste")
			(net "GND")
			(options
				(clearance outline)
				(anchor circle)
			)
			(primitives
				(gr_poly
					(pts
						(arc
							(start 0.3048 0.2032)
							(mid 0.275042 0.275042)
							(end 0.2032 0.3048)
						)
						(arc
							(start -0.2032 0.3048)
							(mid -0.275042 0.275042)
							(end -0.3048 0.2032)
						)
						(arc
							(start -0.3048 -0.2032)
							(mid -0.275042 -0.275042)
							(end -0.2032 -0.3048)
						)
						(arc
							(start 0.2032 -0.3048)
							(mid 0.275042 -0.275042)
							(end 0.3048 -0.2032)
						)
					)
					(width 0)
					(fill yes)
				)
			)
		)
	)
	(footprint ""
		(layer "B.Cu")
		(at 276.729952 -165.248336 90)
		(property "Reference" "R236"
			(at 0 0 90)
			(layer "B.SilkS")
			(hide yes)
			(effects
				(font
					(size 1.27 1.27)
				)
				(justify mirror)
			)
		)
		(property "Value" "100KR2F-L1-GP"
			(at -0.064008 -3.993896 90)
			(unlocked yes)
			(layer "B.Fab")
			(hide yes)
			(effects
				(font
					(size 1.016 1.016)
					(thickness 0.1524)
				)
				(justify mirror)
			)
		)
		(property "Device Type" "R402H16"
			(at -0.064008 -5.517896 90)
			(unlocked yes)
			(layer "B.Fab")
			(hide yes)
			(effects
				(font
					(size 1.016 1.016)
					(thickness 0.1524)
				)
				(justify mirror)
			)
		)
		(duplicate_pad_numbers_are_jumpers no)
		(fp_line
			(start 0.508 -0.9398)
			(end 0.508 0.9398)
			(stroke
				(width 0.1524)
				(type default)
			)
			(layer "B.SilkS")
		)
		(fp_line
			(start -0.508 -0.9398)
			(end 0.508 -0.9398)
			(stroke
				(width 0.1524)
				(type default)
			)
			(layer "B.SilkS")
		)
		(fp_rect
			(start 0.508 0.9398)
			(end -0.508 -0.9398)
			(stroke
				(width 0)
				(type default)
			)
			(fill no)
			(layer "B.CrtYd")
		)
		(fp_rect
			(start 0.508 0.9398)
			(end -0.508 -0.9398)
			(stroke
				(width 0)
				(type default)
			)
			(fill no)
			(layer "B.Fab")
		)
		(pad "1" smd custom
			(at 0 -0.4445 270)
			(size 0.1397 0.1397)
			(layers "B.Cu" "B.Mask" "B.Paste")
			(net "GND")
			(options
				(clearance outline)
				(anchor circle)
			)
			(primitives
				(gr_poly
					(pts
						(arc
							(start -0.1778 0.2794)
							(mid -0.249642 0.249642)
							(end -0.2794 0.1778)
						)
						(arc
							(start -0.2794 -0.1778)
							(mid -0.249642 -0.249642)
							(end -0.1778 -0.2794)
						)
						(arc
							(start 0.1778 -0.2794)
							(mid 0.249642 -0.249642)
							(end 0.2794 -0.1778)
						)
						(arc
							(start 0.2794 0.1778)
							(mid 0.249642 0.249642)
							(end 0.1778 0.2794)
						)
					)
					(width 0)
					(fill yes)
				)
			)
		)
		(pad "2" smd custom
			(at 0 0.4445 270)
			(size 0.1397 0.1397)
			(layers "B.Cu" "B.Mask" "B.Paste")
			(net "TP_BMC0_LPC_LAD2")
			(options
				(clearance outline)
				(anchor circle)
			)
			(primitives
				(gr_poly
					(pts
						(arc
							(start -0.1778 0.2794)
							(mid -0.249642 0.249642)
							(end -0.2794 0.1778)
						)
						(arc
							(start -0.2794 -0.1778)
							(mid -0.249642 -0.249642)
							(end -0.1778 -0.2794)
						)
						(arc
							(start 0.1778 -0.2794)
							(mid 0.249642 -0.249642)
							(end 0.2794 -0.1778)
						)
						(arc
							(start 0.2794 0.1778)
							(mid 0.249642 0.249642)
							(end 0.1778 0.2794)
						)
					)
					(width 0)
					(fill yes)
				)
			)
		)
	)
	(footprint ""
		(layer "B.Cu")
		(at 197.739 -247.142 90)
		(property "Reference" "R626"
			(at 0 0 90)
			(layer "B.SilkS")
			(hide yes)
			(effects
				(font
					(size 1.27 1.27)
				)
				(justify mirror)
			)
		)
		(property "Value" "27KR2F-L-GP"
			(at -0.064008 -3.993896 90)
			(unlocked yes)
			(layer "B.Fab")
			(hide yes)
			(effects
				(font
					(size 1.016 1.016)
					(thickness 0.1524)
				)
				(justify mirror)
			)
		)
		(property "Device Type" "R402H16"
			(at -0.064008 -5.517896 90)
			(unlocked yes)
			(layer "B.Fab")
			(hide yes)
			(effects
				(font
					(size 1.016 1.016)
					(thickness 0.1524)
				)
				(justify mirror)
			)
		)
		(duplicate_pad_numbers_are_jumpers no)
		(fp_line
			(start 0.508 -0.9398)
			(end 0.508 0.9398)
			(stroke
				(width 0.1524)
				(type default)
			)
			(layer "B.SilkS")
		)
		(fp_line
			(start -0.508 -0.9398)
			(end 0.508 -0.9398)
			(stroke
				(width 0.1524)
				(type default)
			)
			(layer "B.SilkS")
		)
		(fp_rect
			(start 0.508 0.9398)
			(end -0.508 -0.9398)
			(stroke
				(width 0)
				(type default)
			)
			(fill no)
			(layer "B.CrtYd")
		)
		(fp_rect
			(start 0.508 0.9398)
			(end -0.508 -0.9398)
			(stroke
				(width 0)
				(type default)
			)
			(fill no)
			(layer "B.Fab")
		)
		(pad "1" smd custom
			(at 0 -0.4445 270)
			(size 0.1397 0.1397)
			(layers "B.Cu" "B.Mask" "B.Paste")
			(net "P12V_PCIE")
			(options
				(clearance outline)
				(anchor circle)
			)
			(primitives
				(gr_poly
					(pts
						(arc
							(start -0.1778 0.2794)
							(mid -0.249642 0.249642)
							(end -0.2794 0.1778)
						)
						(arc
							(start -0.2794 -0.1778)
							(mid -0.249642 -0.249642)
							(end -0.1778 -0.2794)
						)
						(arc
							(start 0.1778 -0.2794)
							(mid 0.249642 -0.249642)
							(end 0.2794 -0.1778)
						)
						(arc
							(start 0.2794 0.1778)
							(mid 0.249642 0.249642)
							(end 0.1778 0.2794)
						)
					)
					(width 0)
					(fill yes)
				)
			)
		)
		(pad "2" smd custom
			(at 0 0.4445 270)
			(size 0.1397 0.1397)
			(layers "B.Cu" "B.Mask" "B.Paste")
			(net "PCIE_MATED#_B")
			(options
				(clearance outline)
				(anchor circle)
			)
			(primitives
				(gr_poly
					(pts
						(arc
							(start -0.1778 0.2794)
							(mid -0.249642 0.249642)
							(end -0.2794 0.1778)
						)
						(arc
							(start -0.2794 -0.1778)
							(mid -0.249642 -0.249642)
							(end -0.1778 -0.2794)
						)
						(arc
							(start 0.1778 -0.2794)
							(mid 0.249642 -0.249642)
							(end 0.2794 -0.1778)
						)
						(arc
							(start 0.2794 0.1778)
							(mid 0.249642 0.249642)
							(end 0.1778 0.2794)
						)
					)
					(width 0)
					(fill yes)
				)
			)
		)
	)
	(footprint ""
		(layer "B.Cu")
		(at 49.60493 -78.158086)
		(property "Reference" "TP189"
			(at 0 0 0)
			(layer "B.SilkS")
			(hide yes)
			(effects
				(font
					(size 1.27 1.27)
				)
				(justify mirror)
			)
		)
		(property "Value" "TPAD32-GP"
			(at 0 -3.166364 0)
			(unlocked yes)
			(layer "B.Fab")
			(hide yes)
			(effects
				(font
					(size 1.016 1.016)
					(thickness 0.1524)
				)
				(justify mirror)
			)
		)
		(property "Device Type" "TPAD32"
			(at 0 -4.690618 0)
			(unlocked yes)
			(layer "B.Fab")
			(hide yes)
			(effects
				(font
					(size 1.016 1.016)
					(thickness 0.1524)
				)
				(justify mirror)
			)
		)
		(duplicate_pad_numbers_are_jumpers no)
		(fp_poly
			(pts
				(arc
					(start 0.4064 0)
					(mid -0.4064 0)
					(end 0.4064 0)
				)
			)
			(stroke
				(width 0)
				(type default)
			)
			(fill no)
			(layer "B.CrtYd")
		)
		(fp_poly
			(pts
				(arc
					(start 0.7112 0)
					(mid -0.7112 0)
					(end 0.7112 0)
				)
			)
			(stroke
				(width 0)
				(type default)
			)
			(fill no)
			(layer "B.Fab")
		)
		(pad "1" smd circle
			(at 0 0 180)
			(size 0.8128 0.8128)
			(layers "B.Cu" "B.Mask" "B.Paste")
			(net "INT_CONN_A_SB4")
		)
	)
	(footprint ""
		(layer "B.Cu")
		(at 113.662206 -41.19626)
		(property "Reference" "STP24"
			(at 0 0 0)
			(layer "B.SilkS")
			(hide yes)
			(effects
				(font
					(size 1.27 1.27)
				)
				(justify mirror)
			)
		)
		(property "Value" "TPAD28"
			(at -0.0127 -1.8034 0)
			(unlocked yes)
			(layer "B.Fab")
			(hide yes)
			(effects
				(font
					(size 1.016 1.016)
					(thickness 0.1524)
				)
				(justify mirror)
			)
		)
		(property "Device Type" "TPAD28"
			(at -0.0127 -3.3274 0)
			(unlocked yes)
			(layer "B.Fab")
			(hide yes)
			(effects
				(font
					(size 1.016 1.016)
					(thickness 0.1524)
				)
				(justify mirror)
			)
		)
		(duplicate_pad_numbers_are_jumpers no)
		(fp_poly
			(pts
				(arc
					(start 0.3556 0)
					(mid -0.3556 0)
					(end 0.3556 0)
				)
			)
			(stroke
				(width 0)
				(type default)
			)
			(fill no)
			(layer "B.CrtYd")
		)
		(fp_poly
			(pts
				(arc
					(start 0.6096 0)
					(mid -0.6096 0)
					(end 0.6096 0)
				)
			)
			(stroke
				(width 0)
				(type default)
			)
			(fill no)
			(layer "B.Fab")
		)
		(pad "1" smd circle
			(at 0 0 180)
			(size 0.7112 0.7112)
			(layers "B.Cu" "B.Mask" "B.Paste")
			(net "IOC_GPIO_38")
		)
	)
	(footprint ""
		(layer "B.Cu")
		(at 95.739966 -52.578)
		(property "Reference" "SC978"
			(at 0 0 0)
			(layer "B.SilkS")
			(hide yes)
			(effects
				(font
					(size 1.27 1.27)
				)
				(justify mirror)
			)
		)
		(property "Value" "SCD1U16V2KX-3GP"
			(at -1.1811 -2.7051 0)
			(unlocked yes)
			(layer "B.Fab")
			(hide yes)
			(effects
				(font
					(size 1.016 1.016)
					(thickness 0.1524)
				)
				(justify mirror)
			)
		)
		(property "Device Type" "C402H22"
			(at -1.1811 -4.2291 0)
			(unlocked yes)
			(layer "B.Fab")
			(hide yes)
			(effects
				(font
					(size 1.016 1.016)
					(thickness 0.1524)
				)
				(justify mirror)
			)
		)
		(duplicate_pad_numbers_are_jumpers no)
		(fp_rect
			(start 0.4318 0.9525)
			(end -0.4318 -0.9525)
			(stroke
				(width 0)
				(type default)
			)
			(fill no)
			(layer "B.CrtYd")
		)
		(fp_rect
			(start 0.4318 0.9525)
			(end -0.4318 -0.9525)
			(stroke
				(width 0)
				(type default)
			)
			(fill no)
			(layer "B.Fab")
		)
		(pad "1" smd custom
			(at 0 -0.4445 180)
			(size 0.1524 0.1524)
			(layers "B.Cu" "B.Mask" "B.Paste")
			(net "P1V8_C")
			(options
				(clearance outline)
				(anchor circle)
			)
			(primitives
				(gr_poly
					(pts
						(arc
							(start 0.3048 0.2032)
							(mid 0.275042 0.275042)
							(end 0.2032 0.3048)
						)
						(arc
							(start -0.2032 0.3048)
							(mid -0.275042 0.275042)
							(end -0.3048 0.2032)
						)
						(arc
							(start -0.3048 -0.2032)
							(mid -0.275042 -0.275042)
							(end -0.2032 -0.3048)
						)
						(arc
							(start 0.2032 -0.3048)
							(mid 0.275042 -0.275042)
							(end 0.3048 -0.2032)
						)
					)
					(width 0)
					(fill yes)
				)
			)
		)
		(pad "2" smd custom
			(at 0 0.4445 180)
			(size 0.1524 0.1524)
			(layers "B.Cu" "B.Mask" "B.Paste")
			(net "GND")
			(options
				(clearance outline)
				(anchor circle)
			)
			(primitives
				(gr_poly
					(pts
						(arc
							(start 0.3048 0.2032)
							(mid 0.275042 0.275042)
							(end 0.2032 0.3048)
						)
						(arc
							(start -0.2032 0.3048)
							(mid -0.275042 0.275042)
							(end -0.3048 0.2032)
						)
						(arc
							(start -0.3048 -0.2032)
							(mid -0.275042 -0.275042)
							(end -0.2032 -0.3048)
						)
						(arc
							(start 0.2032 -0.3048)
							(mid 0.275042 -0.275042)
							(end 0.3048 -0.2032)
						)
					)
					(width 0)
					(fill yes)
				)
			)
		)
	)
	(footprint ""
		(layer "B.Cu")
		(at 93.599 -3.429)
		(property "Reference" "SC1019"
			(at 0 0 0)
			(layer "B.SilkS")
			(hide yes)
			(effects
				(font
					(size 1.27 1.27)
				)
				(justify mirror)
			)
		)
		(property "Value" "SC10U6D3V5KX-4GP"
			(at 0.0762 -6.1214 0)
			(unlocked yes)
			(layer "B.Fab")
			(hide yes)
			(effects
				(font
					(size 1.016 1.016)
					(thickness 0.1524)
				)
				(justify mirror)
			)
		)
		(property "Device Type" "C805H58"
			(at 0.0762 -8.1534 0)
			(unlocked yes)
			(layer "B.Fab")
			(hide yes)
			(effects
				(font
					(size 1.016 1.016)
					(thickness 0.1524)
				)
				(justify mirror)
			)
		)
		(duplicate_pad_numbers_are_jumpers no)
		(fp_line
			(start -0.635 0)
			(end 0.635 0)
			(stroke
				(width 0.508)
				(type default)
			)
			(layer "B.SilkS")
		)
		(fp_rect
			(start 0.9652 1.778)
			(end -0.9652 -1.778)
			(stroke
				(width 0)
				(type default)
			)
			(fill no)
			(layer "B.CrtYd")
		)
		(fp_poly
			(pts
				(xy 0.9652 -1.778) (xy -0.9652 -1.778) (xy -0.9652 1.778) (xy 0.9652 1.778)
			)
			(stroke
				(width 0)
				(type default)
			)
			(fill no)
			(layer "B.Fab")
		)
		(pad "1" smd rect
			(at 0 -0.9652 180)
			(size 1.397 1.143)
			(layers "B.Cu" "B.Mask" "B.Paste")
			(net "P0V955_C")
		)
		(pad "2" smd rect
			(at 0 0.9652 180)
			(size 1.397 1.143)
			(layers "B.Cu" "B.Mask" "B.Paste")
			(net "GND")
		)
	)
	(footprint ""
		(layer "B.Cu")
		(at 116.34597 -82.931 -90)
		(property "Reference" "SC1212"
			(at 0 0 90)
			(layer "B.SilkS")
			(hide yes)
			(effects
				(font
					(size 1.27 1.27)
				)
				(justify mirror)
			)
		)
		(property "Value" "SC1KP50V2KX-1GP"
			(at -1.1811 -2.7051 270)
			(unlocked yes)
			(layer "B.Fab")
			(hide yes)
			(effects
				(font
					(size 1.016 1.016)
					(thickness 0.1524)
				)
				(justify mirror)
			)
		)
		(property "Device Type" "C402H22"
			(at -1.1811 -4.2291 270)
			(unlocked yes)
			(layer "B.Fab")
			(hide yes)
			(effects
				(font
					(size 1.016 1.016)
					(thickness 0.1524)
				)
				(justify mirror)
			)
		)
		(duplicate_pad_numbers_are_jumpers no)
		(fp_rect
			(start 0.4318 0.9525)
			(end -0.4318 -0.9525)
			(stroke
				(width 0)
				(type default)
			)
			(fill no)
			(layer "B.CrtYd")
		)
		(fp_rect
			(start 0.4318 0.9525)
			(end -0.4318 -0.9525)
			(stroke
				(width 0)
				(type default)
			)
			(fill no)
			(layer "B.Fab")
		)
		(pad "1" smd custom
			(at 0 -0.4445 90)
			(size 0.1524 0.1524)
			(layers "B.Cu" "B.Mask" "B.Paste")
			(net "P1V8_E")
			(options
				(clearance outline)
				(anchor circle)
			)
			(primitives
				(gr_poly
					(pts
						(arc
							(start 0.3048 0.2032)
							(mid 0.275042 0.275042)
							(end 0.2032 0.3048)
						)
						(arc
							(start -0.2032 0.3048)
							(mid -0.275042 0.275042)
							(end -0.3048 0.2032)
						)
						(arc
							(start -0.3048 -0.2032)
							(mid -0.275042 -0.275042)
							(end -0.2032 -0.3048)
						)
						(arc
							(start 0.2032 -0.3048)
							(mid 0.275042 -0.275042)
							(end 0.3048 -0.2032)
						)
					)
					(width 0)
					(fill yes)
				)
			)
		)
		(pad "2" smd custom
			(at 0 0.4445 90)
			(size 0.1524 0.1524)
			(layers "B.Cu" "B.Mask" "B.Paste")
			(net "GND")
			(options
				(clearance outline)
				(anchor circle)
			)
			(primitives
				(gr_poly
					(pts
						(arc
							(start 0.3048 0.2032)
							(mid 0.275042 0.275042)
							(end 0.2032 0.3048)
						)
						(arc
							(start -0.2032 0.3048)
							(mid -0.275042 0.275042)
							(end -0.3048 0.2032)
						)
						(arc
							(start -0.3048 -0.2032)
							(mid -0.275042 -0.275042)
							(end -0.2032 -0.3048)
						)
						(arc
							(start 0.2032 -0.3048)
							(mid 0.275042 -0.275042)
							(end 0.3048 -0.2032)
						)
					)
					(width 0)
					(fill yes)
				)
			)
		)
	)
	(footprint ""
		(layer "B.Cu")
		(at 50.87493 -76.761086)
		(property "Reference" "SC1278"
			(at 0 0 0)
			(layer "B.SilkS")
			(hide yes)
			(effects
				(font
					(size 1.27 1.27)
				)
				(justify mirror)
			)
		)
		(property "Value" "SCD01U50V2KX-1GP"
			(at -1.1811 -2.7051 0)
			(unlocked yes)
			(layer "B.Fab")
			(hide yes)
			(effects
				(font
					(size 1.016 1.016)
					(thickness 0.1524)
				)
				(justify mirror)
			)
		)
		(property "Device Type" "C402H22"
			(at -1.1811 -4.2291 0)
			(unlocked yes)
			(layer "B.Fab")
			(hide yes)
			(effects
				(font
					(size 1.016 1.016)
					(thickness 0.1524)
				)
				(justify mirror)
			)
		)
		(duplicate_pad_numbers_are_jumpers no)
		(fp_rect
			(start 0.4318 0.9525)
			(end -0.4318 -0.9525)
			(stroke
				(width 0)
				(type default)
			)
			(fill no)
			(layer "B.CrtYd")
		)
		(fp_rect
			(start 0.4318 0.9525)
			(end -0.4318 -0.9525)
			(stroke
				(width 0)
				(type default)
			)
			(fill no)
			(layer "B.Fab")
		)
		(pad "1" smd custom
			(at 0 -0.4445 180)
			(size 0.1524 0.1524)
			(layers "B.Cu" "B.Mask" "B.Paste")
			(net "SAS_EXP2CONN_RX_P_22")
			(options
				(clearance outline)
				(anchor circle)
			)
			(primitives
				(gr_poly
					(pts
						(arc
							(start 0.3048 0.2032)
							(mid 0.275042 0.275042)
							(end 0.2032 0.3048)
						)
						(arc
							(start -0.2032 0.3048)
							(mid -0.275042 0.275042)
							(end -0.3048 0.2032)
						)
						(arc
							(start -0.3048 -0.2032)
							(mid -0.275042 -0.275042)
							(end -0.2032 -0.3048)
						)
						(arc
							(start 0.2032 -0.3048)
							(mid 0.275042 -0.275042)
							(end 0.3048 -0.2032)
						)
					)
					(width 0)
					(fill yes)
				)
			)
		)
		(pad "2" smd custom
			(at 0 0.4445 180)
			(size 0.1524 0.1524)
			(layers "B.Cu" "B.Mask" "B.Paste")
			(net "MINI_RX_P_22")
			(options
				(clearance outline)
				(anchor circle)
			)
			(primitives
				(gr_poly
					(pts
						(arc
							(start 0.3048 0.2032)
							(mid 0.275042 0.275042)
							(end 0.2032 0.3048)
						)
						(arc
							(start -0.2032 0.3048)
							(mid -0.275042 0.275042)
							(end -0.3048 0.2032)
						)
						(arc
							(start -0.3048 -0.2032)
							(mid -0.275042 -0.275042)
							(end -0.2032 -0.3048)
						)
						(arc
							(start 0.2032 -0.3048)
							(mid 0.275042 -0.275042)
							(end 0.3048 -0.2032)
						)
					)
					(width 0)
					(fill yes)
				)
			)
		)
	)
)
